(kicad_pcb
	(version 20260206)
	(generator "pcbnew")
	(generator_version "10.0")
	(general
		(thickness 1.6)
		(legacy_teardrops no)
	)
	(paper "A4")
	(title_block
		(title "04192023_DAF0TMB3IC0_F0TG_MB_C_brd_V02_OCP.brd")
		(comment 1 "Grand Teton / footprints 5716-5721 of 8354")
	)
	(layers
		(0 "F.Cu" signal "TOP")
		(4 "In1.Cu" signal "GND")
		(6 "In2.Cu" signal "IN1")
		(8 "In3.Cu" signal "GND1")
		(10 "In4.Cu" signal "IN2")
		(12 "In5.Cu" signal "GND2")
		(14 "In6.Cu" signal "IN3")
		(16 "In7.Cu" signal "GND3")
		(18 "In8.Cu" signal "VCC")
		(20 "In9.Cu" signal "VCC1")
		(22 "In10.Cu" signal "GND4")
		(24 "In11.Cu" signal "IN4")
		(26 "In12.Cu" signal "GND5")
		(28 "In13.Cu" signal "IN5")
		(30 "In14.Cu" signal "GND6")
		(32 "In15.Cu" signal "IN6")
		(34 "In16.Cu" signal "GND7")
		(2 "B.Cu" signal "BOTTOM")
		(9 "F.Adhes" user "F.Adhesive")
		(11 "B.Adhes" user "B.Adhesive")
		(13 "F.Paste" user "Package Geometry/Pastemask Top")
		(15 "B.Paste" user "Package Geometry/Pastemask Bottom")
		(5 "F.SilkS" user "Ref Des/Silkscreen Top")
		(7 "B.SilkS" user "Ref Des/Silkscreen Bottom")
		(1 "F.Mask" user "Board Geometry/Soldermask Top")
		(3 "B.Mask" user "Board Geometry/Soldermask Bottom")
		(17 "Dwgs.User" user "User.Drawings")
		(19 "Cmts.User" user "User.Comments")
		(21 "Eco1.User" user "User.Eco1")
		(23 "Eco2.User" user "User.Eco2")
		(25 "Edge.Cuts" user "Board Geometry/Outline")
		(27 "Margin" user)
		(31 "F.CrtYd" user "Package Geometry/Place Bound Top")
		(29 "B.CrtYd" user "Package Geometry/Place Bound Bottom")
		(35 "F.Fab" user "Ref Des/Assembly Top")
		(33 "B.Fab" user "Ref Des/Assembly Bottom")
	)
	(footprint ""
		(layer "B.Cu")
		(at 391.585958 -321.179952)
		(property "Reference" "R473"
			(at 0 0 0)
			(layer "B.SilkS")
			(hide yes)
			(effects
				(font
					(size 1.27 1.27)
				)
				(justify mirror)
			)
		)
		(property "Value" ""
			(at 0 0 0)
			(layer "B.Fab")
			(effects
				(font
					(size 1.27 1.27)
				)
				(justify mirror)
			)
		)
		(duplicate_pad_numbers_are_jumpers no)
		(fp_line
			(start -0.7874 -0.4064)
			(end -0.7874 0.4064)
			(stroke
				(width 0.1524)
				(type default)
			)
			(layer "B.SilkS")
		)
		(fp_line
			(start -0.7874 0.4064)
			(end 0.7874 0.4064)
			(stroke
				(width 0.1524)
				(type default)
			)
			(layer "B.SilkS")
		)
		(fp_line
			(start 0.7874 -0.4064)
			(end -0.7874 -0.4064)
			(stroke
				(width 0.1524)
				(type default)
			)
			(layer "B.SilkS")
		)
		(fp_line
			(start 0.7874 0.4064)
			(end 0.7874 -0.4064)
			(stroke
				(width 0.1524)
				(type default)
			)
			(layer "B.SilkS")
		)
		(fp_line
			(start -0.67945 -0.3048)
			(end -0.67945 0.3048)
			(stroke
				(width 0.1)
				(type default)
			)
			(layer "B.Fab")
		)
		(fp_line
			(start -0.67945 0.3048)
			(end -0.120396 0.3048)
			(stroke
				(width 0.1)
				(type default)
			)
			(layer "B.Fab")
		)
		(fp_line
			(start -0.12065 -0.3048)
			(end -0.67945 -0.3048)
			(stroke
				(width 0.1)
				(type default)
			)
			(layer "B.Fab")
		)
		(fp_line
			(start -0.12065 -0.2794)
			(end -0.12065 -0.3048)
			(stroke
				(width 0.1)
				(type default)
			)
			(layer "B.Fab")
		)
		(fp_line
			(start -0.120396 0.2794)
			(end 0.12065 0.2794)
			(stroke
				(width 0.1)
				(type default)
			)
			(layer "B.Fab")
		)
		(fp_line
			(start -0.120396 0.3048)
			(end -0.120396 0.2794)
			(stroke
				(width 0.1)
				(type default)
			)
			(layer "B.Fab")
		)
		(fp_line
			(start 0.12065 -0.305054)
			(end 0.12065 -0.2794)
			(stroke
				(width 0.1)
				(type default)
			)
			(layer "B.Fab")
		)
		(fp_line
			(start 0.12065 -0.2794)
			(end -0.12065 -0.2794)
			(stroke
				(width 0.1)
				(type default)
			)
			(layer "B.Fab")
		)
		(fp_line
			(start 0.12065 0.2794)
			(end 0.12065 0.3048)
			(stroke
				(width 0.1)
				(type default)
			)
			(layer "B.Fab")
		)
		(fp_line
			(start 0.12065 0.3048)
			(end 0.67945 0.3048)
			(stroke
				(width 0.1)
				(type default)
			)
			(layer "B.Fab")
		)
		(fp_line
			(start 0.67945 -0.305054)
			(end 0.12065 -0.305054)
			(stroke
				(width 0.1)
				(type default)
			)
			(layer "B.Fab")
		)
		(fp_line
			(start 0.67945 0.3048)
			(end 0.67945 -0.305054)
			(stroke
				(width 0.1)
				(type default)
			)
			(layer "B.Fab")
		)
		(pad "1" smd circle
			(at 0.40005 0 180)
			(size 0 0)
			(layers "B.Cu" "B.Mask" "B.Paste")
			(net "CLK_ESPI_CPU0_CLK1")
		)
		(pad "2" smd circle
			(at -0.40005 0 180)
			(size 0 0)
			(layers "B.Cu" "B.Mask" "B.Paste")
			(net "CLK_ESPI_CPU0_R_CLK1")
		)
	)
	(footprint ""
		(layer "B.Cu")
		(at 209.441034 -73.168002 180)
		(property "Reference" "C641"
			(at 0 0 0)
			(layer "B.SilkS")
			(hide yes)
			(effects
				(font
					(size 1.27 1.27)
				)
				(justify mirror)
			)
		)
		(property "Value" ""
			(at 0 0 0)
			(layer "B.Fab")
			(effects
				(font
					(size 1.27 1.27)
				)
				(justify mirror)
			)
		)
		(duplicate_pad_numbers_are_jumpers no)
		(fp_line
			(start 0.7874 0.4064)
			(end 0.7874 -0.4064)
			(stroke
				(width 0.1524)
				(type default)
			)
			(layer "B.SilkS")
		)
		(fp_line
			(start 0.7874 -0.4064)
			(end -0.7874 -0.4064)
			(stroke
				(width 0.1524)
				(type default)
			)
			(layer "B.SilkS")
		)
		(fp_line
			(start -0.7874 0.4064)
			(end 0.7874 0.4064)
			(stroke
				(width 0.1524)
				(type default)
			)
			(layer "B.SilkS")
		)
		(fp_line
			(start -0.7874 -0.4064)
			(end -0.7874 0.4064)
			(stroke
				(width 0.1524)
				(type default)
			)
			(layer "B.SilkS")
		)
		(fp_line
			(start 0.67945 0.3048)
			(end 0.67945 -0.305054)
			(stroke
				(width 0.1)
				(type default)
			)
			(layer "B.Fab")
		)
		(fp_line
			(start 0.67945 -0.305054)
			(end 0.12065 -0.305054)
			(stroke
				(width 0.1)
				(type default)
			)
			(layer "B.Fab")
		)
		(fp_line
			(start 0.12065 0.3048)
			(end 0.67945 0.3048)
			(stroke
				(width 0.1)
				(type default)
			)
			(layer "B.Fab")
		)
		(fp_line
			(start 0.12065 0.2794)
			(end 0.12065 0.3048)
			(stroke
				(width 0.1)
				(type default)
			)
			(layer "B.Fab")
		)
		(fp_line
			(start 0.12065 -0.2794)
			(end -0.12065 -0.2794)
			(stroke
				(width 0.1)
				(type default)
			)
			(layer "B.Fab")
		)
		(fp_line
			(start 0.12065 -0.305054)
			(end 0.12065 -0.2794)
			(stroke
				(width 0.1)
				(type default)
			)
			(layer "B.Fab")
		)
		(fp_line
			(start -0.120396 0.3048)
			(end -0.120396 0.2794)
			(stroke
				(width 0.1)
				(type default)
			)
			(layer "B.Fab")
		)
		(fp_line
			(start -0.120396 0.2794)
			(end 0.12065 0.2794)
			(stroke
				(width 0.1)
				(type default)
			)
			(layer "B.Fab")
		)
		(fp_line
			(start -0.12065 -0.2794)
			(end -0.12065 -0.3048)
			(stroke
				(width 0.1)
				(type default)
			)
			(layer "B.Fab")
		)
		(fp_line
			(start -0.12065 -0.3048)
			(end -0.67945 -0.3048)
			(stroke
				(width 0.1)
				(type default)
			)
			(layer "B.Fab")
		)
		(fp_line
			(start -0.67945 0.3048)
			(end -0.120396 0.3048)
			(stroke
				(width 0.1)
				(type default)
			)
			(layer "B.Fab")
		)
		(fp_line
			(start -0.67945 -0.3048)
			(end -0.67945 0.3048)
			(stroke
				(width 0.1)
				(type default)
			)
			(layer "B.Fab")
		)
		(pad "1" smd circle
			(at 0.40005 0)
			(size 0 0)
			(layers "B.Cu" "B.Mask" "B.Paste")
			(net "P3V3_AUX")
		)
		(pad "2" smd circle
			(at -0.40005 0)
			(size 0 0)
			(layers "B.Cu" "B.Mask" "B.Paste")
			(net "GND")
		)
	)
	(footprint ""
		(layer "B.Cu")
		(at 383.38887 -181.684676 90)
		(property "Reference" "PR344"
			(at 0 0 90)
			(layer "B.SilkS")
			(hide yes)
			(effects
				(font
					(size 1.27 1.27)
				)
				(justify mirror)
			)
		)
		(property "Value" ""
			(at 0 0 90)
			(layer "B.Fab")
			(effects
				(font
					(size 1.27 1.27)
				)
				(justify mirror)
			)
		)
		(duplicate_pad_numbers_are_jumpers no)
		(fp_line
			(start 0.7874 -0.4064)
			(end -0.7874 -0.4064)
			(stroke
				(width 0.1524)
				(type default)
			)
			(layer "B.SilkS")
		)
		(fp_line
			(start -0.7874 -0.4064)
			(end -0.7874 0.4064)
			(stroke
				(width 0.1524)
				(type default)
			)
			(layer "B.SilkS")
		)
		(fp_line
			(start 0.7874 0.4064)
			(end 0.7874 -0.4064)
			(stroke
				(width 0.1524)
				(type default)
			)
			(layer "B.SilkS")
		)
		(fp_line
			(start -0.7874 0.4064)
			(end 0.7874 0.4064)
			(stroke
				(width 0.1524)
				(type default)
			)
			(layer "B.SilkS")
		)
		(fp_line
			(start 0.67945 -0.305054)
			(end 0.12065 -0.305054)
			(stroke
				(width 0.1)
				(type default)
			)
			(layer "B.Fab")
		)
		(fp_line
			(start 0.12065 -0.305054)
			(end 0.12065 -0.2794)
			(stroke
				(width 0.1)
				(type default)
			)
			(layer "B.Fab")
		)
		(fp_line
			(start -0.12065 -0.3048)
			(end -0.67945 -0.3048)
			(stroke
				(width 0.1)
				(type default)
			)
			(layer "B.Fab")
		)
		(fp_line
			(start -0.67945 -0.3048)
			(end -0.67945 0.3048)
			(stroke
				(width 0.1)
				(type default)
			)
			(layer "B.Fab")
		)
		(fp_line
			(start 0.12065 -0.2794)
			(end -0.12065 -0.2794)
			(stroke
				(width 0.1)
				(type default)
			)
			(layer "B.Fab")
		)
		(fp_line
			(start -0.12065 -0.2794)
			(end -0.12065 -0.3048)
			(stroke
				(width 0.1)
				(type default)
			)
			(layer "B.Fab")
		)
		(fp_line
			(start 0.12065 0.2794)
			(end 0.12065 0.3048)
			(stroke
				(width 0.1)
				(type default)
			)
			(layer "B.Fab")
		)
		(fp_line
			(start -0.120396 0.2794)
			(end 0.12065 0.2794)
			(stroke
				(width 0.1)
				(type default)
			)
			(layer "B.Fab")
		)
		(fp_line
			(start 0.67945 0.3048)
			(end 0.67945 -0.305054)
			(stroke
				(width 0.1)
				(type default)
			)
			(layer "B.Fab")
		)
		(fp_line
			(start 0.12065 0.3048)
			(end 0.67945 0.3048)
			(stroke
				(width 0.1)
				(type default)
			)
			(layer "B.Fab")
		)
		(fp_line
			(start -0.120396 0.3048)
			(end -0.120396 0.2794)
			(stroke
				(width 0.1)
				(type default)
			)
			(layer "B.Fab")
		)
		(fp_line
			(start -0.67945 0.3048)
			(end -0.120396 0.3048)
			(stroke
				(width 0.1)
				(type default)
			)
			(layer "B.Fab")
		)
		(pad "1" smd circle
			(at 0.40005 0 270)
			(size 0 0)
			(layers "B.Cu" "B.Mask" "B.Paste")
			(net "PVDDCR_CPU0_P0_PVCC")
		)
		(pad "2" smd circle
			(at -0.40005 0 270)
			(size 0 0)
			(layers "B.Cu" "B.Mask" "B.Paste")
			(net "PVDDCR_CPU0_P0_VCC3")
		)
	)
	(footprint ""
		(layer "B.Cu")
		(at 237.236 -219.075 90)
		(property "Reference" "C26"
			(at 0 0 90)
			(layer "B.SilkS")
			(hide yes)
			(effects
				(font
					(size 1.27 1.27)
				)
				(justify mirror)
			)
		)
		(property "Value" ""
			(at 0 0 90)
			(layer "B.Fab")
			(effects
				(font
					(size 1.27 1.27)
				)
				(justify mirror)
			)
		)
		(duplicate_pad_numbers_are_jumpers no)
		(fp_line
			(start 0.7874 -0.4064)
			(end -0.7874 -0.4064)
			(stroke
				(width 0.1524)
				(type default)
			)
			(layer "B.SilkS")
		)
		(fp_line
			(start -0.7874 -0.4064)
			(end -0.7874 0.4064)
			(stroke
				(width 0.1524)
				(type default)
			)
			(layer "B.SilkS")
		)
		(fp_line
			(start 0.7874 0.4064)
			(end 0.7874 -0.4064)
			(stroke
				(width 0.1524)
				(type default)
			)
			(layer "B.SilkS")
		)
		(fp_line
			(start -0.7874 0.4064)
			(end 0.7874 0.4064)
			(stroke
				(width 0.1524)
				(type default)
			)
			(layer "B.SilkS")
		)
		(fp_line
			(start 0.67945 -0.305054)
			(end 0.12065 -0.305054)
			(stroke
				(width 0.1)
				(type default)
			)
			(layer "B.Fab")
		)
		(fp_line
			(start 0.12065 -0.305054)
			(end 0.12065 -0.2794)
			(stroke
				(width 0.1)
				(type default)
			)
			(layer "B.Fab")
		)
		(fp_line
			(start -0.12065 -0.3048)
			(end -0.67945 -0.3048)
			(stroke
				(width 0.1)
				(type default)
			)
			(layer "B.Fab")
		)
		(fp_line
			(start -0.67945 -0.3048)
			(end -0.67945 0.3048)
			(stroke
				(width 0.1)
				(type default)
			)
			(layer "B.Fab")
		)
		(fp_line
			(start 0.12065 -0.2794)
			(end -0.12065 -0.2794)
			(stroke
				(width 0.1)
				(type default)
			)
			(layer "B.Fab")
		)
		(fp_line
			(start -0.12065 -0.2794)
			(end -0.12065 -0.3048)
			(stroke
				(width 0.1)
				(type default)
			)
			(layer "B.Fab")
		)
		(fp_line
			(start 0.12065 0.2794)
			(end 0.12065 0.3048)
			(stroke
				(width 0.1)
				(type default)
			)
			(layer "B.Fab")
		)
		(fp_line
			(start -0.120396 0.2794)
			(end 0.12065 0.2794)
			(stroke
				(width 0.1)
				(type default)
			)
			(layer "B.Fab")
		)
		(fp_line
			(start 0.67945 0.3048)
			(end 0.67945 -0.305054)
			(stroke
				(width 0.1)
				(type default)
			)
			(layer "B.Fab")
		)
		(fp_line
			(start 0.12065 0.3048)
			(end 0.67945 0.3048)
			(stroke
				(width 0.1)
				(type default)
			)
			(layer "B.Fab")
		)
		(fp_line
			(start -0.120396 0.3048)
			(end -0.120396 0.2794)
			(stroke
				(width 0.1)
				(type default)
			)
			(layer "B.Fab")
		)
		(fp_line
			(start -0.67945 0.3048)
			(end -0.120396 0.3048)
			(stroke
				(width 0.1)
				(type default)
			)
			(layer "B.Fab")
		)
		(pad "1" smd circle
			(at 0.40005 0 270)
			(size 0 0)
			(layers "B.Cu" "B.Mask" "B.Paste")
			(net "P3V3")
		)
		(pad "2" smd circle
			(at -0.40005 0 270)
			(size 0 0)
			(layers "B.Cu" "B.Mask" "B.Paste")
			(net "GND")
		)
	)
	(footprint ""
		(layer "B.Cu")
		(at 101.41839 -340.998556 -90)
		(property "Reference" "PR427"
			(at 0 0 90)
			(layer "B.SilkS")
			(hide yes)
			(effects
				(font
					(size 1.27 1.27)
				)
				(justify mirror)
			)
		)
		(property "Value" ""
			(at 0 0 90)
			(layer "B.Fab")
			(effects
				(font
					(size 1.27 1.27)
				)
				(justify mirror)
			)
		)
		(duplicate_pad_numbers_are_jumpers no)
		(fp_line
			(start -0.7874 0.4064)
			(end 0.7874 0.4064)
			(stroke
				(width 0.1524)
				(type default)
			)
			(layer "B.SilkS")
		)
		(fp_line
			(start 0.7874 0.4064)
			(end 0.7874 -0.4064)
			(stroke
				(width 0.1524)
				(type default)
			)
			(layer "B.SilkS")
		)
		(fp_line
			(start -0.7874 -0.4064)
			(end -0.7874 0.4064)
			(stroke
				(width 0.1524)
				(type default)
			)
			(layer "B.SilkS")
		)
		(fp_line
			(start 0.7874 -0.4064)
			(end -0.7874 -0.4064)
			(stroke
				(width 0.1524)
				(type default)
			)
			(layer "B.SilkS")
		)
		(fp_line
			(start -0.67945 0.3048)
			(end -0.120396 0.3048)
			(stroke
				(width 0.1)
				(type default)
			)
			(layer "B.Fab")
		)
		(fp_line
			(start -0.120396 0.3048)
			(end -0.120396 0.2794)
			(stroke
				(width 0.1)
				(type default)
			)
			(layer "B.Fab")
		)
		(fp_line
			(start 0.12065 0.3048)
			(end 0.67945 0.3048)
			(stroke
				(width 0.1)
				(type default)
			)
			(layer "B.Fab")
		)
		(fp_line
			(start 0.67945 0.3048)
			(end 0.67945 -0.305054)
			(stroke
				(width 0.1)
				(type default)
			)
			(layer "B.Fab")
		)
		(fp_line
			(start -0.120396 0.2794)
			(end 0.12065 0.2794)
			(stroke
				(width 0.1)
				(type default)
			)
			(layer "B.Fab")
		)
		(fp_line
			(start 0.12065 0.2794)
			(end 0.12065 0.3048)
			(stroke
				(width 0.1)
				(type default)
			)
			(layer "B.Fab")
		)
		(fp_line
			(start -0.12065 -0.2794)
			(end -0.12065 -0.3048)
			(stroke
				(width 0.1)
				(type default)
			)
			(layer "B.Fab")
		)
		(fp_line
			(start 0.12065 -0.2794)
			(end -0.12065 -0.2794)
			(stroke
				(width 0.1)
				(type default)
			)
			(layer "B.Fab")
		)
		(fp_line
			(start -0.67945 -0.3048)
			(end -0.67945 0.3048)
			(stroke
				(width 0.1)
				(type default)
			)
			(layer "B.Fab")
		)
		(fp_line
			(start -0.12065 -0.3048)
			(end -0.67945 -0.3048)
			(stroke
				(width 0.1)
				(type default)
			)
			(layer "B.Fab")
		)
		(fp_line
			(start 0.12065 -0.305054)
			(end 0.12065 -0.2794)
			(stroke
				(width 0.1)
				(type default)
			)
			(layer "B.Fab")
		)
		(fp_line
			(start 0.67945 -0.305054)
			(end 0.12065 -0.305054)
			(stroke
				(width 0.1)
				(type default)
			)
			(layer "B.Fab")
		)
		(pad "1" smd circle
			(at 0.40005 0 90)
			(size 0 0)
			(layers "B.Cu" "B.Mask" "B.Paste")
			(net "PVDDCR_CPU1_P1_PVCC")
		)
		(pad "2" smd circle
			(at -0.40005 0 90)
			(size 0 0)
			(layers "B.Cu" "B.Mask" "B.Paste")
			(net "PVDDCR_CPU1_P1_VCC6")
		)
	)
	(footprint ""
		(layer "B.Cu")
		(at 200.023222 -123.831096 180)
		(property "Reference" "R2846"
			(at 0 0 0)
			(layer "B.SilkS")
			(hide yes)
			(effects
				(font
					(size 1.27 1.27)
				)
				(justify mirror)
			)
		)
		(property "Value" ""
			(at 0 0 0)
			(layer "B.Fab")
			(effects
				(font
					(size 1.27 1.27)
				)
				(justify mirror)
			)
		)
		(duplicate_pad_numbers_are_jumpers no)
		(fp_line
			(start 0.7874 0.4064)
			(end 0.7874 -0.4064)
			(stroke
				(width 0.1524)
				(type default)
			)
			(layer "B.SilkS")
		)
		(fp_line
			(start 0.7874 -0.4064)
			(end -0.7874 -0.4064)
			(stroke
				(width 0.1524)
				(type default)
			)
			(layer "B.SilkS")
		)
		(fp_line
			(start -0.7874 0.4064)
			(end 0.7874 0.4064)
			(stroke
				(width 0.1524)
				(type default)
			)
			(layer "B.SilkS")
		)
		(fp_line
			(start -0.7874 -0.4064)
			(end -0.7874 0.4064)
			(stroke
				(width 0.1524)
				(type default)
			)
			(layer "B.SilkS")
		)
		(fp_line
			(start 0.67945 0.3048)
			(end 0.67945 -0.305054)
			(stroke
				(width 0.1)
				(type default)
			)
			(layer "B.Fab")
		)
		(fp_line
			(start 0.67945 -0.305054)
			(end 0.12065 -0.305054)
			(stroke
				(width 0.1)
				(type default)
			)
			(layer "B.Fab")
		)
		(fp_line
			(start 0.12065 0.3048)
			(end 0.67945 0.3048)
			(stroke
				(width 0.1)
				(type default)
			)
			(layer "B.Fab")
		)
		(fp_line
			(start 0.12065 0.2794)
			(end 0.12065 0.3048)
			(stroke
				(width 0.1)
				(type default)
			)
			(layer "B.Fab")
		)
		(fp_line
			(start 0.12065 -0.2794)
			(end -0.12065 -0.2794)
			(stroke
				(width 0.1)
				(type default)
			)
			(layer "B.Fab")
		)
		(fp_line
			(start 0.12065 -0.305054)
			(end 0.12065 -0.2794)
			(stroke
				(width 0.1)
				(type default)
			)
			(layer "B.Fab")
		)
		(fp_line
			(start -0.120396 0.3048)
			(end -0.120396 0.2794)
			(stroke
				(width 0.1)
				(type default)
			)
			(layer "B.Fab")
		)
		(fp_line
			(start -0.120396 0.2794)
			(end 0.12065 0.2794)
			(stroke
				(width 0.1)
				(type default)
			)
			(layer "B.Fab")
		)
		(fp_line
			(start -0.12065 -0.2794)
			(end -0.12065 -0.3048)
			(stroke
				(width 0.1)
				(type default)
			)
			(layer "B.Fab")
		)
		(fp_line
			(start -0.12065 -0.3048)
			(end -0.67945 -0.3048)
			(stroke
				(width 0.1)
				(type default)
			)
			(layer "B.Fab")
		)
		(fp_line
			(start -0.67945 0.3048)
			(end -0.120396 0.3048)
			(stroke
				(width 0.1)
				(type default)
			)
			(layer "B.Fab")
		)
		(fp_line
			(start -0.67945 -0.3048)
			(end -0.67945 0.3048)
			(stroke
				(width 0.1)
				(type default)
			)
			(layer "B.Fab")
		)
		(pad "1" smd circle
			(at 0.40005 0)
			(size 0 0)
			(layers "B.Cu" "B.Mask" "B.Paste")
			(net "BIC_MONITER_ISO_R")
		)
		(pad "2" smd circle
			(at -0.40005 0)
			(size 0 0)
			(layers "B.Cu" "B.Mask" "B.Paste")
			(net "BIC_MONITER_ISO")
		)
	)
)
